(kicad_pcb
	(version 20260206)
	(generator "pcbnew")
	(generator_version "10.0")
	(general
		(thickness 1.6)
		(legacy_teardrops no)
	)
	(paper "A4")
	(title_block
		(title "4HDD Backplane_Layout.brd")
		(comment 1 "Tioga Pass / footprints 1-8 of 97")
	)
	(layers
		(0 "F.Cu" signal "TOP")
		(4 "In1.Cu" signal "L2GND")
		(6 "In2.Cu" signal "L3")
		(8 "In3.Cu" signal "L4")
		(10 "In4.Cu" signal "L5GND")
		(2 "B.Cu" signal "BOTTOM")
		(9 "F.Adhes" user "F.Adhesive")
		(11 "B.Adhes" user "B.Adhesive")
		(13 "F.Paste" user "Package Geometry/Pastemask Top")
		(15 "B.Paste" user "Package Geometry/Pastemask Bottom")
		(5 "F.SilkS" user "Ref Des/Silkscreen Top")
		(7 "B.SilkS" user "Ref Des/Silkscreen Bottom")
		(1 "F.Mask" user "Board Geometry/Soldermask Top")
		(3 "B.Mask" user "Board Geometry/Soldermask Bottom")
		(17 "Dwgs.User" user "User.Drawings")
		(19 "Cmts.User" user "User.Comments")
		(21 "Eco1.User" user "User.Eco1")
		(23 "Eco2.User" user "User.Eco2")
		(25 "Edge.Cuts" user "Board Geometry/Outline")
		(27 "Margin" user)
		(31 "F.CrtYd" user "Package Geometry/Place Bound Top")
		(29 "B.CrtYd" user "Package Geometry/Place Bound Bottom")
		(35 "F.Fab" user "Ref Des/Assembly Top")
		(33 "B.Fab" user "Ref Des/Assembly Bottom")
	)
	(footprint ""
		(layer "F.Cu")
		(at 83.058 -36.068 90)
		(property "Reference" "R140"
			(at 0 0 90)
			(layer "F.SilkS")
			(hide yes)
			(effects
				(font
					(size 1.27 1.27)
				)
			)
		)
		(property "Value" "200KR2F-L-GP"
			(at 0.064008 -3.993896 90)
			(unlocked yes)
			(layer "F.Fab")
			(hide yes)
			(effects
				(font
					(size 1.016 1.016)
					(thickness 0.1524)
				)
			)
		)
		(property "Device Type" "R402H16"
			(at 0.064008 -5.517896 90)
			(unlocked yes)
			(layer "F.Fab")
			(hide yes)
			(effects
				(font
					(size 1.016 1.016)
					(thickness 0.1524)
				)
			)
		)
		(duplicate_pad_numbers_are_jumpers no)
		(fp_line
			(start 0.508 -0.9398)
			(end -0.508 -0.9398)
			(stroke
				(width 0.1524)
				(type default)
			)
			(layer "F.SilkS")
		)
		(fp_line
			(start -0.508 -0.9398)
			(end -0.508 0.9398)
			(stroke
				(width 0.1524)
				(type default)
			)
			(layer "F.SilkS")
		)
		(fp_rect
			(start -0.508 0.9398)
			(end 0.508 -0.9398)
			(stroke
				(width 0)
				(type default)
			)
			(fill no)
			(layer "F.CrtYd")
		)
		(fp_rect
			(start -0.508 0.9398)
			(end 0.508 -0.9398)
			(stroke
				(width 0)
				(type default)
			)
			(fill no)
			(layer "F.Fab")
		)
		(pad "1" smd custom
			(at 0 -0.4445 90)
			(size 0.1397 0.1397)
			(layers "F.Cu" "F.Mask" "F.Paste")
			(net "SW_SW_R_0")
			(options
				(clearance outline)
				(anchor circle)
			)
			(primitives
				(gr_poly
					(pts
						(arc
							(start -0.1778 -0.2794)
							(mid -0.249642 -0.249642)
							(end -0.2794 -0.1778)
						)
						(arc
							(start -0.2794 0.1778)
							(mid -0.249642 0.249642)
							(end -0.1778 0.2794)
						)
						(arc
							(start 0.1778 0.2794)
							(mid 0.249642 0.249642)
							(end 0.2794 0.1778)
						)
						(arc
							(start 0.2794 -0.1778)
							(mid 0.249642 -0.249642)
							(end 0.1778 -0.2794)
						)
					)
					(width 0)
					(fill yes)
				)
			)
		)
		(pad "2" smd custom
			(at 0 0.4445 90)
			(size 0.1397 0.1397)
			(layers "F.Cu" "F.Mask" "F.Paste")
			(net "SW_SW_R_N_0")
			(options
				(clearance outline)
				(anchor circle)
			)
			(primitives
				(gr_poly
					(pts
						(arc
							(start -0.1778 -0.2794)
							(mid -0.249642 -0.249642)
							(end -0.2794 -0.1778)
						)
						(arc
							(start -0.2794 0.1778)
							(mid -0.249642 0.249642)
							(end -0.1778 0.2794)
						)
						(arc
							(start 0.1778 0.2794)
							(mid 0.249642 0.249642)
							(end 0.2794 0.1778)
						)
						(arc
							(start 0.2794 -0.1778)
							(mid 0.249642 -0.249642)
							(end 0.1778 -0.2794)
						)
					)
					(width 0)
					(fill yes)
				)
			)
		)
	)
	(footprint ""
		(layer "F.Cu")
		(at 51.347624 -8.483346 90)
		(property "Reference" "C15"
			(at 0 0 90)
			(layer "F.SilkS")
			(hide yes)
			(effects
				(font
					(size 1.27 1.27)
				)
			)
		)
		(property "Value" "SC10U10V5KX-L1-GP"
			(at -0.0762 -6.1214 90)
			(unlocked yes)
			(layer "F.Fab")
			(hide yes)
			(effects
				(font
					(size 1.016 1.016)
					(thickness 0.1524)
				)
			)
		)
		(property "Device Type" "C805H58"
			(at -0.0762 -8.1534 90)
			(unlocked yes)
			(layer "F.Fab")
			(hide yes)
			(effects
				(font
					(size 1.016 1.016)
					(thickness 0.1524)
				)
			)
		)
		(duplicate_pad_numbers_are_jumpers no)
		(fp_line
			(start 0.635 0)
			(end -0.635 0)
			(stroke
				(width 0.508)
				(type default)
			)
			(layer "F.SilkS")
		)
		(fp_rect
			(start -0.9652 1.778)
			(end 0.9652 -1.778)
			(stroke
				(width 0)
				(type default)
			)
			(fill no)
			(layer "F.CrtYd")
		)
		(fp_poly
			(pts
				(xy -0.9652 -1.778) (xy 0.9652 -1.778) (xy 0.9652 1.778) (xy -0.9652 1.778)
			)
			(stroke
				(width 0)
				(type default)
			)
			(fill no)
			(layer "F.Fab")
		)
		(pad "1" smd rect
			(at 0 -0.9652 90)
			(size 1.397 1.143)
			(layers "F.Cu" "F.Mask" "F.Paste")
			(net "P5V_SW_L")
		)
		(pad "2" smd rect
			(at 0 0.9652 90)
			(size 1.397 1.143)
			(layers "F.Cu" "F.Mask" "F.Paste")
			(net "GND")
		)
	)
	(footprint ""
		(layer "F.Cu")
		(at 122.8598 -57.277)
		(property "Reference" "R2"
			(at 0 0 0)
			(layer "F.SilkS")
			(hide yes)
			(effects
				(font
					(size 1.27 1.27)
				)
			)
		)
		(property "Value" "10KR2J-3-GP"
			(at 0.064008 -3.993896 0)
			(unlocked yes)
			(layer "F.Fab")
			(hide yes)
			(effects
				(font
					(size 1.016 1.016)
					(thickness 0.1524)
				)
			)
		)
		(property "Device Type" "R402H16"
			(at 0.064008 -5.517896 0)
			(unlocked yes)
			(layer "F.Fab")
			(hide yes)
			(effects
				(font
					(size 1.016 1.016)
					(thickness 0.1524)
				)
			)
		)
		(duplicate_pad_numbers_are_jumpers no)
		(fp_line
			(start -0.508 -0.9398)
			(end -0.508 0.9398)
			(stroke
				(width 0.1524)
				(type default)
			)
			(layer "F.SilkS")
		)
		(fp_line
			(start 0.508 -0.9398)
			(end -0.508 -0.9398)
			(stroke
				(width 0.1524)
				(type default)
			)
			(layer "F.SilkS")
		)
		(fp_rect
			(start -0.508 0.9398)
			(end 0.508 -0.9398)
			(stroke
				(width 0)
				(type default)
			)
			(fill no)
			(layer "F.CrtYd")
		)
		(fp_rect
			(start -0.508 0.9398)
			(end 0.508 -0.9398)
			(stroke
				(width 0)
				(type default)
			)
			(fill no)
			(layer "F.Fab")
		)
		(pad "1" smd custom
			(at 0 -0.4445)
			(size 0.1397 0.1397)
			(layers "F.Cu" "F.Mask" "F.Paste")
			(net "P3V3")
			(options
				(clearance outline)
				(anchor circle)
			)
			(primitives
				(gr_poly
					(pts
						(arc
							(start -0.1778 -0.2794)
							(mid -0.249642 -0.249642)
							(end -0.2794 -0.1778)
						)
						(arc
							(start -0.2794 0.1778)
							(mid -0.249642 0.249642)
							(end -0.1778 0.2794)
						)
						(arc
							(start 0.1778 0.2794)
							(mid 0.249642 0.249642)
							(end 0.2794 0.1778)
						)
						(arc
							(start 0.2794 -0.1778)
							(mid 0.249642 -0.249642)
							(end 0.1778 -0.2794)
						)
					)
					(width 0)
					(fill yes)
				)
			)
		)
		(pad "2" smd custom
			(at 0 0.4445)
			(size 0.1397 0.1397)
			(layers "F.Cu" "F.Mask" "F.Paste")
			(net "HBA_PRSNT0_N")
			(options
				(clearance outline)
				(anchor circle)
			)
			(primitives
				(gr_poly
					(pts
						(arc
							(start -0.1778 -0.2794)
							(mid -0.249642 -0.249642)
							(end -0.2794 -0.1778)
						)
						(arc
							(start -0.2794 0.1778)
							(mid -0.249642 0.249642)
							(end -0.1778 0.2794)
						)
						(arc
							(start 0.1778 0.2794)
							(mid 0.249642 0.249642)
							(end 0.2794 0.1778)
						)
						(arc
							(start 0.2794 -0.1778)
							(mid 0.249642 -0.249642)
							(end 0.1778 -0.2794)
						)
					)
					(width 0)
					(fill yes)
				)
			)
		)
	)
	(footprint ""
		(layer "F.Cu")
		(at 77.0001 -61.699902)
		(property "Reference" "H4"
			(at 0 0 0)
			(layer "F.SilkS")
			(hide yes)
			(effects
				(font
					(size 1.27 1.27)
				)
			)
		)
		(property "Value" "HOLET217B237R130-GP"
			(at -5.08 -0.4572 0)
			(unlocked yes)
			(layer "F.Fab")
			(hide yes)
			(effects
				(font
					(size 1.016 1.016)
					(thickness 0.1524)
				)
			)
		)
		(property "Device Type" "HOLET217B237R130"
			(at -5.08 -1.9812 0)
			(unlocked yes)
			(layer "F.Fab")
			(hide yes)
			(effects
				(font
					(size 1.016 1.016)
					(thickness 0.1524)
				)
			)
		)
		(duplicate_pad_numbers_are_jumpers no)
		(fp_poly
			(pts
				(arc
					(start 3.3147 0)
					(mid -3.3147 0)
					(end 3.3147 0)
				)
			)
			(stroke
				(width 0)
				(type default)
			)
			(fill no)
			(layer "B.CrtYd")
		)
		(fp_poly
			(pts
				(arc
					(start 3.0607 0)
					(mid -3.0607 0)
					(end 3.0607 0)
				)
			)
			(stroke
				(width 0)
				(type default)
			)
			(fill no)
			(layer "F.CrtYd")
		)
		(fp_poly
			(pts
				(arc
					(start 3.3147 0)
					(mid -3.3147 0)
					(end 3.3147 0)
				)
			)
			(stroke
				(width 0)
				(type default)
			)
			(fill no)
			(layer "B.Fab")
		)
		(fp_poly
			(pts
				(arc
					(start 3.0607 0)
					(mid -3.0607 0)
					(end 3.0607 0)
				)
			)
			(stroke
				(width 0)
				(type default)
			)
			(fill no)
			(layer "F.Fab")
		)
		(pad "1" thru_hole circle
			(at 0 0)
			(size 5.5118 5.5118)
			(drill 3.302)
			(layers "*.Cu" "*.Mask")
			(remove_unused_layers no)
			(net "GND")
			(clearance -0.5969)
			(thermal_gap 0.3048)
			(padstack
				(mode front_inner_back)
				(layer "Inner"
					(shape circle)
					(size 3.7084 3.7084)
					(clearance 0.3048)
				)
				(layer "B.Cu"
					(shape circle)
					(size 6.0198 6.0198)
					(clearance -0.8509)
				)
			)
		)
	)
	(footprint ""
		(layer "F.Cu")
		(at 78.105 -33.909 90)
		(property "Reference" "R138"
			(at 0 0 90)
			(layer "F.SilkS")
			(hide yes)
			(effects
				(font
					(size 1.27 1.27)
				)
			)
		)
		(property "Value" "4K7R2J-2-GP"
			(at 0.064008 -3.993896 90)
			(unlocked yes)
			(layer "F.Fab")
			(hide yes)
			(effects
				(font
					(size 1.016 1.016)
					(thickness 0.1524)
				)
			)
		)
		(property "Device Type" "R402H16"
			(at 0.064008 -5.517896 90)
			(unlocked yes)
			(layer "F.Fab")
			(hide yes)
			(effects
				(font
					(size 1.016 1.016)
					(thickness 0.1524)
				)
			)
		)
		(duplicate_pad_numbers_are_jumpers no)
		(fp_line
			(start 0.508 -0.9398)
			(end -0.508 -0.9398)
			(stroke
				(width 0.1524)
				(type default)
			)
			(layer "F.SilkS")
		)
		(fp_line
			(start -0.508 -0.9398)
			(end -0.508 0.9398)
			(stroke
				(width 0.1524)
				(type default)
			)
			(layer "F.SilkS")
		)
		(fp_rect
			(start -0.508 0.9398)
			(end 0.508 -0.9398)
			(stroke
				(width 0)
				(type default)
			)
			(fill no)
			(layer "F.CrtYd")
		)
		(fp_rect
			(start -0.508 0.9398)
			(end 0.508 -0.9398)
			(stroke
				(width 0)
				(type default)
			)
			(fill no)
			(layer "F.Fab")
		)
		(pad "1" smd custom
			(at 0 -0.4445 90)
			(size 0.1397 0.1397)
			(layers "F.Cu" "F.Mask" "F.Paste")
			(net "P3V3")
			(options
				(clearance outline)
				(anchor circle)
			)
			(primitives
				(gr_poly
					(pts
						(arc
							(start -0.1778 -0.2794)
							(mid -0.249642 -0.249642)
							(end -0.2794 -0.1778)
						)
						(arc
							(start -0.2794 0.1778)
							(mid -0.249642 0.249642)
							(end -0.1778 0.2794)
						)
						(arc
							(start 0.1778 0.2794)
							(mid 0.249642 0.249642)
							(end 0.2794 0.1778)
						)
						(arc
							(start 0.2794 -0.1778)
							(mid 0.249642 -0.249642)
							(end 0.1778 -0.2794)
						)
					)
					(width 0)
					(fill yes)
				)
			)
		)
		(pad "2" smd custom
			(at 0 0.4445 90)
			(size 0.1397 0.1397)
			(layers "F.Cu" "F.Mask" "F.Paste")
			(net "PWR_EN_D_0")
			(options
				(clearance outline)
				(anchor circle)
			)
			(primitives
				(gr_poly
					(pts
						(arc
							(start -0.1778 -0.2794)
							(mid -0.249642 -0.249642)
							(end -0.2794 -0.1778)
						)
						(arc
							(start -0.2794 0.1778)
							(mid -0.249642 0.249642)
							(end -0.1778 0.2794)
						)
						(arc
							(start 0.1778 0.2794)
							(mid 0.249642 0.249642)
							(end 0.2794 0.1778)
						)
						(arc
							(start 0.2794 -0.1778)
							(mid 0.249642 -0.249642)
							(end 0.1778 -0.2794)
						)
					)
					(width 0)
					(fill yes)
				)
			)
		)
	)
	(footprint ""
		(layer "F.Cu")
		(at 48.1838 -8.1534 -90)
		(property "Reference" "R9"
			(at 0 0 270)
			(layer "F.SilkS")
			(hide yes)
			(effects
				(font
					(size 1.27 1.27)
				)
			)
		)
		(property "Value" "10R3F-GP"
			(at -0.0254 -2.5146 270)
			(unlocked yes)
			(layer "F.Fab")
			(hide yes)
			(effects
				(font
					(size 1.016 1.016)
					(thickness 0.1524)
				)
			)
		)
		(property "Device Type" "R603H22"
			(at -0.0254 -4.0386 270)
			(unlocked yes)
			(layer "F.Fab")
			(hide yes)
			(effects
				(font
					(size 1.016 1.016)
					(thickness 0.1524)
				)
			)
		)
		(duplicate_pad_numbers_are_jumpers no)
		(fp_line
			(start -0.4826 0)
			(end -0.2032 0)
			(stroke
				(width 0.2032)
				(type default)
			)
			(layer "F.SilkS")
		)
		(fp_line
			(start 0.2032 0)
			(end 0.4826 0)
			(stroke
				(width 0.2032)
				(type default)
			)
			(layer "F.SilkS")
		)
		(fp_rect
			(start -0.5842 1.3335)
			(end 0.5842 -1.3335)
			(stroke
				(width 0)
				(type default)
			)
			(fill no)
			(layer "F.CrtYd")
		)
		(fp_rect
			(start -0.5842 1.3335)
			(end 0.5842 -1.3335)
			(stroke
				(width 0)
				(type default)
			)
			(fill no)
			(layer "F.Fab")
		)
		(pad "1" smd custom
			(at 0 -0.762 270)
			(size 0.2159 0.2159)
			(layers "F.Cu" "F.Mask" "F.Paste")
			(net "P5V_SW_L")
			(options
				(clearance outline)
				(anchor circle)
			)
			(primitives
				(gr_poly
					(pts
						(arc
							(start -0.3302 -0.4318)
							(mid -0.402042 -0.402042)
							(end -0.4318 -0.3302)
						)
						(arc
							(start -0.4318 0.3302)
							(mid -0.402042 0.402042)
							(end -0.3302 0.4318)
						)
						(arc
							(start 0.3302 0.4318)
							(mid 0.402042 0.402042)
							(end 0.4318 0.3302)
						)
						(arc
							(start 0.4318 -0.3302)
							(mid 0.402042 -0.402042)
							(end 0.3302 -0.4318)
						)
					)
					(width 0)
					(fill yes)
				)
			)
		)
		(pad "2" smd custom
			(at 0 0.762 270)
			(size 0.2159 0.2159)
			(layers "F.Cu" "F.Mask" "F.Paste")
			(net "5V_PRE_3")
			(options
				(clearance outline)
				(anchor circle)
			)
			(primitives
				(gr_poly
					(pts
						(arc
							(start -0.3302 -0.4318)
							(mid -0.402042 -0.402042)
							(end -0.4318 -0.3302)
						)
						(arc
							(start -0.4318 0.3302)
							(mid -0.402042 0.402042)
							(end -0.3302 0.4318)
						)
						(arc
							(start 0.3302 0.4318)
							(mid 0.402042 0.402042)
							(end 0.4318 0.3302)
						)
						(arc
							(start 0.4318 -0.3302)
							(mid 0.402042 -0.402042)
							(end 0.3302 -0.4318)
						)
					)
					(width 0)
					(fill yes)
				)
			)
		)
	)
	(footprint ""
		(layer "F.Cu")
		(at 47.117 -19.05 -90)
		(property "Reference" "R10"
			(at 0 0 270)
			(layer "F.SilkS")
			(hide yes)
			(effects
				(font
					(size 1.27 1.27)
				)
			)
		)
		(property "Value" "10R3F-GP"
			(at -0.0254 -2.5146 270)
			(unlocked yes)
			(layer "F.Fab")
			(hide yes)
			(effects
				(font
					(size 1.016 1.016)
					(thickness 0.1524)
				)
			)
		)
		(property "Device Type" "R603H22"
			(at -0.0254 -4.0386 270)
			(unlocked yes)
			(layer "F.Fab")
			(hide yes)
			(effects
				(font
					(size 1.016 1.016)
					(thickness 0.1524)
				)
			)
		)
		(duplicate_pad_numbers_are_jumpers no)
		(fp_line
			(start -0.4826 0)
			(end -0.2032 0)
			(stroke
				(width 0.2032)
				(type default)
			)
			(layer "F.SilkS")
		)
		(fp_line
			(start 0.2032 0)
			(end 0.4826 0)
			(stroke
				(width 0.2032)
				(type default)
			)
			(layer "F.SilkS")
		)
		(fp_rect
			(start -0.5842 1.3335)
			(end 0.5842 -1.3335)
			(stroke
				(width 0)
				(type default)
			)
			(fill no)
			(layer "F.CrtYd")
		)
		(fp_rect
			(start -0.5842 1.3335)
			(end 0.5842 -1.3335)
			(stroke
				(width 0)
				(type default)
			)
			(fill no)
			(layer "F.Fab")
		)
		(pad "1" smd custom
			(at 0 -0.762 270)
			(size 0.2159 0.2159)
			(layers "F.Cu" "F.Mask" "F.Paste")
			(net "P5V_SW_L")
			(options
				(clearance outline)
				(anchor circle)
			)
			(primitives
				(gr_poly
					(pts
						(arc
							(start -0.3302 -0.4318)
							(mid -0.402042 -0.402042)
							(end -0.4318 -0.3302)
						)
						(arc
							(start -0.4318 0.3302)
							(mid -0.402042 0.402042)
							(end -0.3302 0.4318)
						)
						(arc
							(start 0.3302 0.4318)
							(mid 0.402042 0.402042)
							(end 0.4318 0.3302)
						)
						(arc
							(start 0.4318 -0.3302)
							(mid 0.402042 -0.402042)
							(end 0.3302 -0.4318)
						)
					)
					(width 0)
					(fill yes)
				)
			)
		)
		(pad "2" smd custom
			(at 0 0.762 270)
			(size 0.2159 0.2159)
			(layers "F.Cu" "F.Mask" "F.Paste")
			(net "5V_PRE_2")
			(options
				(clearance outline)
				(anchor circle)
			)
			(primitives
				(gr_poly
					(pts
						(arc
							(start -0.3302 -0.4318)
							(mid -0.402042 -0.402042)
							(end -0.4318 -0.3302)
						)
						(arc
							(start -0.4318 0.3302)
							(mid -0.402042 0.402042)
							(end -0.3302 0.4318)
						)
						(arc
							(start 0.3302 0.4318)
							(mid 0.402042 0.402042)
							(end 0.4318 0.3302)
						)
						(arc
							(start 0.4318 -0.3302)
							(mid 0.402042 -0.402042)
							(end 0.3302 -0.4318)
						)
					)
					(width 0)
					(fill yes)
				)
			)
		)
	)
	(footprint ""
		(layer "F.Cu")
		(at 3.999992 -4.020058)
		(property "Reference" "H1"
			(at 0 0 0)
			(layer "F.SilkS")
			(hide yes)
			(effects
				(font
					(size 1.27 1.27)
				)
			)
		)
		(property "Value" "HOLET217B237R166-GP"
			(at -5.08 -0.4572 0)
			(unlocked yes)
			(layer "F.Fab")
			(hide yes)
			(effects
				(font
					(size 1.016 1.016)
					(thickness 0.1524)
				)
			)
		)
		(property "Device Type" "HOLET217B237R166"
			(at -5.08 -1.9812 0)
			(unlocked yes)
			(layer "F.Fab")
			(hide yes)
			(effects
				(font
					(size 1.016 1.016)
					(thickness 0.1524)
				)
			)
		)
		(duplicate_pad_numbers_are_jumpers no)
		(fp_poly
			(pts
				(arc
					(start 3.3147 0)
					(mid -3.3147 0)
					(end 3.3147 0)
				)
			)
			(stroke
				(width 0)
				(type default)
			)
			(fill no)
			(layer "B.CrtYd")
		)
		(fp_poly
			(pts
				(arc
					(start 3.0607 0)
					(mid -3.0607 0)
					(end 3.0607 0)
				)
			)
			(stroke
				(width 0)
				(type default)
			)
			(fill no)
			(layer "F.CrtYd")
		)
		(fp_poly
			(pts
				(arc
					(start 3.3147 0)
					(mid -3.3147 0)
					(end 3.3147 0)
				)
			)
			(stroke
				(width 0)
				(type default)
			)
			(fill no)
			(layer "B.Fab")
		)
		(fp_poly
			(pts
				(arc
					(start 3.0607 0)
					(mid -3.0607 0)
					(end 3.0607 0)
				)
			)
			(stroke
				(width 0)
				(type default)
			)
			(fill no)
			(layer "F.Fab")
		)
		(pad "1" thru_hole circle
			(at 0 0)
			(size 5.5118 5.5118)
			(drill 4.2164)
			(layers "*.Cu" "*.Mask")
			(remove_unused_layers no)
			(net "GND")
			(clearance -0.1397)
			(thermal_gap 0.3048)
			(padstack
				(mode front_inner_back)
				(layer "Inner"
					(shape circle)
					(size 4.6228 4.6228)
					(clearance 0.3048)
				)
				(layer "B.Cu"
					(shape circle)
					(size 6.0198 6.0198)
					(clearance -0.3937)
				)
			)
		)
	)
)
